(kicad_pcb
	(version 20260206)
	(generator "pcbnew")
	(generator_version "10.0")
	(general
		(thickness 1.6)
		(legacy_teardrops no)
	)
	(paper "A4")
	(title_block
		(title "peb — Lightning_PEB_BRD.brd")
		(comment 1 "Lightning (Wiwynn / Facebook NVMe JBOF) / footprints 162-168 of 2563")
	)
	(layers
		(0 "F.Cu" signal "TOP")
		(4 "In1.Cu" signal "L2GND")
		(6 "In2.Cu" signal "L3")
		(8 "In3.Cu" signal "L4VCC")
		(10 "In4.Cu" signal "L5VCC")
		(12 "In5.Cu" signal "L6")
		(14 "In6.Cu" signal "L7GND")
		(2 "B.Cu" signal "BOTTOM")
		(9 "F.Adhes" user "F.Adhesive")
		(11 "B.Adhes" user "B.Adhesive")
		(13 "F.Paste" user "Package Geometry/Pastemask Top")
		(15 "B.Paste" user "Package Geometry/Pastemask Bottom")
		(5 "F.SilkS" user "Ref Des/Silkscreen Top")
		(7 "B.SilkS" user "Ref Des/Silkscreen Bottom")
		(1 "F.Mask" user "Board Geometry/Soldermask Top")
		(3 "B.Mask" user "Board Geometry/Soldermask Bottom")
		(17 "Dwgs.User" user "User.Drawings")
		(19 "Cmts.User" user "User.Comments")
		(21 "Eco1.User" user "User.Eco1")
		(23 "Eco2.User" user "User.Eco2")
		(25 "Edge.Cuts" user "Board Geometry/Outline")
		(27 "Margin" user)
		(31 "F.CrtYd" user "Package Geometry/Place Bound Top")
		(29 "B.CrtYd" user "Package Geometry/Place Bound Bottom")
		(35 "F.Fab" user "Ref Des/Assembly Top")
		(33 "B.Fab" user "Ref Des/Assembly Bottom")
	)
	(footprint ""
		(layer "F.Cu")
		(at 131.236466 -208.8769 180)
		(property "Reference" "R7927"
			(at 0 0 180)
			(layer "F.SilkS")
			(hide yes)
			(effects
				(font
					(size 1.27 1.27)
				)
			)
		)
		(property "Value" "0R2J-2-GP"
			(at 0.064008 -3.993896 180)
			(unlocked yes)
			(layer "F.Fab")
			(hide yes)
			(effects
				(font
					(size 1.016 1.016)
					(thickness 0.1524)
				)
			)
		)
		(property "Device Type" "R402H16"
			(at 0.064008 -5.517896 180)
			(unlocked yes)
			(layer "F.Fab")
			(hide yes)
			(effects
				(font
					(size 1.016 1.016)
					(thickness 0.1524)
				)
			)
		)
		(duplicate_pad_numbers_are_jumpers no)
		(fp_line
			(start 0.508 -0.9398)
			(end -0.508 -0.9398)
			(stroke
				(width 0.1524)
				(type default)
			)
			(layer "F.SilkS")
		)
		(fp_line
			(start -0.508 -0.9398)
			(end -0.508 0.9398)
			(stroke
				(width 0.1524)
				(type default)
			)
			(layer "F.SilkS")
		)
		(fp_rect
			(start -0.508 0.9398)
			(end 0.508 -0.9398)
			(stroke
				(width 0)
				(type default)
			)
			(fill no)
			(layer "F.CrtYd")
		)
		(fp_rect
			(start -0.508 0.9398)
			(end 0.508 -0.9398)
			(stroke
				(width 0)
				(type default)
			)
			(fill no)
			(layer "F.Fab")
		)
		(pad "1" smd custom
			(at 0 -0.4445 180)
			(size 0.1397 0.1397)
			(layers "F.Cu" "F.Mask" "F.Paste")
			(net "SSD_PRSNT#7")
			(options
				(clearance outline)
				(anchor circle)
			)
			(primitives
				(gr_poly
					(pts
						(arc
							(start -0.1778 -0.2794)
							(mid -0.249642 -0.249642)
							(end -0.2794 -0.1778)
						)
						(arc
							(start -0.2794 0.1778)
							(mid -0.249642 0.249642)
							(end -0.1778 0.2794)
						)
						(arc
							(start 0.1778 0.2794)
							(mid 0.249642 0.249642)
							(end 0.2794 0.1778)
						)
						(arc
							(start 0.2794 -0.1778)
							(mid 0.249642 -0.249642)
							(end 0.1778 -0.2794)
						)
					)
					(width 0)
					(fill yes)
				)
			)
		)
		(pad "2" smd custom
			(at 0 0.4445 180)
			(size 0.1397 0.1397)
			(layers "F.Cu" "F.Mask" "F.Paste")
			(net "SSD_PRSNT#7_R")
			(options
				(clearance outline)
				(anchor circle)
			)
			(primitives
				(gr_poly
					(pts
						(arc
							(start -0.1778 -0.2794)
							(mid -0.249642 -0.249642)
							(end -0.2794 -0.1778)
						)
						(arc
							(start -0.2794 0.1778)
							(mid -0.249642 0.249642)
							(end -0.1778 0.2794)
						)
						(arc
							(start 0.1778 0.2794)
							(mid 0.249642 0.249642)
							(end 0.2794 0.1778)
						)
						(arc
							(start 0.2794 -0.1778)
							(mid 0.249642 -0.249642)
							(end 0.1778 -0.2794)
						)
					)
					(width 0)
					(fill yes)
				)
			)
		)
	)
	(footprint ""
		(layer "F.Cu")
		(at 153.45918 -84.41436 180)
		(property "Reference" "C719"
			(at 0 0 180)
			(layer "F.SilkS")
			(hide yes)
			(effects
				(font
					(size 1.27 1.27)
				)
			)
		)
		(property "Value" "SC1U10V2KX-4-GP"
			(at 1.1811 -2.7051 180)
			(unlocked yes)
			(layer "F.Fab")
			(hide yes)
			(effects
				(font
					(size 1.016 1.016)
					(thickness 0.1524)
				)
			)
		)
		(property "Device Type" "C402H22"
			(at 1.1811 -4.2291 180)
			(unlocked yes)
			(layer "F.Fab")
			(hide yes)
			(effects
				(font
					(size 1.016 1.016)
					(thickness 0.1524)
				)
			)
		)
		(duplicate_pad_numbers_are_jumpers no)
		(fp_rect
			(start -0.4318 0.9525)
			(end 0.4318 -0.9525)
			(stroke
				(width 0)
				(type default)
			)
			(fill no)
			(layer "F.CrtYd")
		)
		(fp_rect
			(start -0.4318 0.9525)
			(end 0.4318 -0.9525)
			(stroke
				(width 0)
				(type default)
			)
			(fill no)
			(layer "F.Fab")
		)
		(pad "1" smd custom
			(at 0 -0.4445 180)
			(size 0.1524 0.1524)
			(layers "F.Cu" "F.Mask" "F.Paste")
			(net "P1V8_STBY")
			(options
				(clearance outline)
				(anchor circle)
			)
			(primitives
				(gr_poly
					(pts
						(arc
							(start 0.3048 -0.2032)
							(mid 0.275042 -0.275042)
							(end 0.2032 -0.3048)
						)
						(arc
							(start -0.2032 -0.3048)
							(mid -0.275042 -0.275042)
							(end -0.3048 -0.2032)
						)
						(arc
							(start -0.3048 0.2032)
							(mid -0.275042 0.275042)
							(end -0.2032 0.3048)
						)
						(arc
							(start 0.2032 0.3048)
							(mid 0.275042 0.275042)
							(end 0.3048 0.2032)
						)
					)
					(width 0)
					(fill yes)
				)
			)
		)
		(pad "2" smd custom
			(at 0 0.4445 180)
			(size 0.1524 0.1524)
			(layers "F.Cu" "F.Mask" "F.Paste")
			(net "GND")
			(options
				(clearance outline)
				(anchor circle)
			)
			(primitives
				(gr_poly
					(pts
						(arc
							(start 0.3048 -0.2032)
							(mid 0.275042 -0.275042)
							(end 0.2032 -0.3048)
						)
						(arc
							(start -0.2032 -0.3048)
							(mid -0.275042 -0.275042)
							(end -0.3048 -0.2032)
						)
						(arc
							(start -0.3048 0.2032)
							(mid -0.275042 0.275042)
							(end -0.2032 0.3048)
						)
						(arc
							(start 0.2032 0.3048)
							(mid 0.275042 0.275042)
							(end 0.3048 0.2032)
						)
					)
					(width 0)
					(fill yes)
				)
			)
		)
	)
	(footprint ""
		(layer "F.Cu")
		(at 139.326874 -92.85732)
		(property "Reference" "PR74"
			(at 0 0 0)
			(layer "F.SilkS")
			(hide yes)
			(effects
				(font
					(size 1.27 1.27)
				)
			)
		)
		(property "Value" "0R3J-0-U-GP"
			(at -0.0254 -2.5146 0)
			(unlocked yes)
			(layer "F.Fab")
			(hide yes)
			(effects
				(font
					(size 1.016 1.016)
					(thickness 0.1524)
				)
			)
		)
		(property "Device Type" "R603H22"
			(at -0.0254 -4.0386 0)
			(unlocked yes)
			(layer "F.Fab")
			(hide yes)
			(effects
				(font
					(size 1.016 1.016)
					(thickness 0.1524)
				)
			)
		)
		(duplicate_pad_numbers_are_jumpers no)
		(fp_line
			(start -0.4826 0)
			(end -0.2032 0)
			(stroke
				(width 0.2032)
				(type default)
			)
			(layer "F.SilkS")
		)
		(fp_line
			(start 0.2032 0)
			(end 0.4826 0)
			(stroke
				(width 0.2032)
				(type default)
			)
			(layer "F.SilkS")
		)
		(fp_rect
			(start -0.5842 1.3335)
			(end 0.5842 -1.3335)
			(stroke
				(width 0)
				(type default)
			)
			(fill no)
			(layer "F.CrtYd")
		)
		(fp_rect
			(start -0.5842 1.3335)
			(end 0.5842 -1.3335)
			(stroke
				(width 0)
				(type default)
			)
			(fill no)
			(layer "F.Fab")
		)
		(pad "1" smd custom
			(at 0 -0.762)
			(size 0.2159 0.2159)
			(layers "F.Cu" "F.Mask" "F.Paste")
			(net "P3V3_STBY_PG")
			(options
				(clearance outline)
				(anchor circle)
			)
			(primitives
				(gr_poly
					(pts
						(arc
							(start -0.3302 -0.4318)
							(mid -0.402042 -0.402042)
							(end -0.4318 -0.3302)
						)
						(arc
							(start -0.4318 0.3302)
							(mid -0.402042 0.402042)
							(end -0.3302 0.4318)
						)
						(arc
							(start 0.3302 0.4318)
							(mid 0.402042 0.402042)
							(end 0.4318 0.3302)
						)
						(arc
							(start 0.4318 -0.3302)
							(mid 0.402042 -0.402042)
							(end 0.3302 -0.4318)
						)
					)
					(width 0)
					(fill yes)
				)
			)
		)
		(pad "2" smd custom
			(at 0 0.762)
			(size 0.2159 0.2159)
			(layers "F.Cu" "F.Mask" "F.Paste")
			(net "VR_P1V8_STBY_EN_R")
			(options
				(clearance outline)
				(anchor circle)
			)
			(primitives
				(gr_poly
					(pts
						(arc
							(start -0.3302 -0.4318)
							(mid -0.402042 -0.402042)
							(end -0.4318 -0.3302)
						)
						(arc
							(start -0.4318 0.3302)
							(mid -0.402042 0.402042)
							(end -0.3302 0.4318)
						)
						(arc
							(start 0.3302 0.4318)
							(mid 0.402042 0.402042)
							(end 0.4318 0.3302)
						)
						(arc
							(start 0.4318 -0.3302)
							(mid 0.402042 -0.402042)
							(end 0.3302 -0.4318)
						)
					)
					(width 0)
					(fill yes)
				)
			)
		)
	)
	(footprint ""
		(layer "F.Cu")
		(at 219.329 -7.112 90)
		(property "Reference" "R663"
			(at 0 0 90)
			(layer "F.SilkS")
			(hide yes)
			(effects
				(font
					(size 1.27 1.27)
				)
			)
		)
		(property "Value" "100KR2F-L1-GP"
			(at 0.064008 -3.993896 90)
			(unlocked yes)
			(layer "F.Fab")
			(hide yes)
			(effects
				(font
					(size 1.016 1.016)
					(thickness 0.1524)
				)
			)
		)
		(property "Device Type" "R402H16"
			(at 0.064008 -5.517896 90)
			(unlocked yes)
			(layer "F.Fab")
			(hide yes)
			(effects
				(font
					(size 1.016 1.016)
					(thickness 0.1524)
				)
			)
		)
		(duplicate_pad_numbers_are_jumpers no)
		(fp_line
			(start 0.508 -0.9398)
			(end -0.508 -0.9398)
			(stroke
				(width 0.1524)
				(type default)
			)
			(layer "F.SilkS")
		)
		(fp_line
			(start -0.508 -0.9398)
			(end -0.508 0.9398)
			(stroke
				(width 0.1524)
				(type default)
			)
			(layer "F.SilkS")
		)
		(fp_rect
			(start -0.508 0.9398)
			(end 0.508 -0.9398)
			(stroke
				(width 0)
				(type default)
			)
			(fill no)
			(layer "F.CrtYd")
		)
		(fp_rect
			(start -0.508 0.9398)
			(end 0.508 -0.9398)
			(stroke
				(width 0)
				(type default)
			)
			(fill no)
			(layer "F.Fab")
		)
		(pad "1" smd custom
			(at 0 -0.4445 90)
			(size 0.1397 0.1397)
			(layers "F.Cu" "F.Mask" "F.Paste")
			(net "P3V3_STBY")
			(options
				(clearance outline)
				(anchor circle)
			)
			(primitives
				(gr_poly
					(pts
						(arc
							(start -0.1778 -0.2794)
							(mid -0.249642 -0.249642)
							(end -0.2794 -0.1778)
						)
						(arc
							(start -0.2794 0.1778)
							(mid -0.249642 0.249642)
							(end -0.1778 0.2794)
						)
						(arc
							(start 0.1778 0.2794)
							(mid 0.249642 0.249642)
							(end 0.2794 0.1778)
						)
						(arc
							(start 0.2794 -0.1778)
							(mid 0.249642 -0.249642)
							(end 0.1778 -0.2794)
						)
					)
					(width 0)
					(fill yes)
				)
			)
		)
		(pad "2" smd custom
			(at 0 0.4445 90)
			(size 0.1397 0.1397)
			(layers "F.Cu" "F.Mask" "F.Paste")
			(net "EEPROM_A2")
			(options
				(clearance outline)
				(anchor circle)
			)
			(primitives
				(gr_poly
					(pts
						(arc
							(start -0.1778 -0.2794)
							(mid -0.249642 -0.249642)
							(end -0.2794 -0.1778)
						)
						(arc
							(start -0.2794 0.1778)
							(mid -0.249642 0.249642)
							(end -0.1778 0.2794)
						)
						(arc
							(start 0.1778 0.2794)
							(mid 0.249642 0.249642)
							(end 0.2794 0.1778)
						)
						(arc
							(start 0.2794 -0.1778)
							(mid 0.249642 -0.249642)
							(end 0.1778 -0.2794)
						)
					)
					(width 0)
					(fill yes)
				)
			)
		)
	)
	(footprint ""
		(layer "F.Cu")
		(at 220.829124 -190.601092)
		(property "Reference" "R7950"
			(at 0 0 0)
			(layer "F.SilkS")
			(hide yes)
			(effects
				(font
					(size 1.27 1.27)
				)
			)
		)
		(property "Value" "0R2J-2-GP"
			(at 0.064008 -3.993896 0)
			(unlocked yes)
			(layer "F.Fab")
			(hide yes)
			(effects
				(font
					(size 1.016 1.016)
					(thickness 0.1524)
				)
			)
		)
		(property "Device Type" "R402H16"
			(at 0.064008 -5.517896 0)
			(unlocked yes)
			(layer "F.Fab")
			(hide yes)
			(effects
				(font
					(size 1.016 1.016)
					(thickness 0.1524)
				)
			)
		)
		(duplicate_pad_numbers_are_jumpers no)
		(fp_line
			(start -0.508 -0.9398)
			(end -0.508 0.9398)
			(stroke
				(width 0.1524)
				(type default)
			)
			(layer "F.SilkS")
		)
		(fp_line
			(start 0.508 -0.9398)
			(end -0.508 -0.9398)
			(stroke
				(width 0.1524)
				(type default)
			)
			(layer "F.SilkS")
		)
		(fp_rect
			(start -0.508 0.9398)
			(end 0.508 -0.9398)
			(stroke
				(width 0)
				(type default)
			)
			(fill no)
			(layer "F.CrtYd")
		)
		(fp_rect
			(start -0.508 0.9398)
			(end 0.508 -0.9398)
			(stroke
				(width 0)
				(type default)
			)
			(fill no)
			(layer "F.Fab")
		)
		(pad "1" smd custom
			(at 0 -0.4445)
			(size 0.1397 0.1397)
			(layers "F.Cu" "F.Mask" "F.Paste")
			(net "SSD_ATNLED#3")
			(options
				(clearance outline)
				(anchor circle)
			)
			(primitives
				(gr_poly
					(pts
						(arc
							(start -0.1778 -0.2794)
							(mid -0.249642 -0.249642)
							(end -0.2794 -0.1778)
						)
						(arc
							(start -0.2794 0.1778)
							(mid -0.249642 0.249642)
							(end -0.1778 0.2794)
						)
						(arc
							(start 0.1778 0.2794)
							(mid 0.249642 0.249642)
							(end 0.2794 0.1778)
						)
						(arc
							(start 0.2794 -0.1778)
							(mid 0.249642 -0.249642)
							(end 0.1778 -0.2794)
						)
					)
					(width 0)
					(fill yes)
				)
			)
		)
		(pad "2" smd custom
			(at 0 0.4445)
			(size 0.1397 0.1397)
			(layers "F.Cu" "F.Mask" "F.Paste")
			(net "SSD_ATNLED#3_R")
			(options
				(clearance outline)
				(anchor circle)
			)
			(primitives
				(gr_poly
					(pts
						(arc
							(start -0.1778 -0.2794)
							(mid -0.249642 -0.249642)
							(end -0.2794 -0.1778)
						)
						(arc
							(start -0.2794 0.1778)
							(mid -0.249642 0.249642)
							(end -0.1778 0.2794)
						)
						(arc
							(start 0.1778 0.2794)
							(mid 0.249642 0.249642)
							(end 0.2794 0.1778)
						)
						(arc
							(start 0.2794 -0.1778)
							(mid 0.249642 -0.249642)
							(end 0.1778 -0.2794)
						)
					)
					(width 0)
					(fill yes)
				)
			)
		)
	)
	(footprint ""
		(layer "F.Cu")
		(at 328.549 -99.568 180)
		(property "Reference" "R4167"
			(at 0 0 180)
			(layer "F.SilkS")
			(hide yes)
			(effects
				(font
					(size 1.27 1.27)
				)
			)
		)
		(property "Value" "4K7R2F-GP"
			(at 0.064008 -3.993896 180)
			(unlocked yes)
			(layer "F.Fab")
			(hide yes)
			(effects
				(font
					(size 1.016 1.016)
					(thickness 0.1524)
				)
			)
		)
		(property "Device Type" "R402H16"
			(at 0.064008 -5.517896 180)
			(unlocked yes)
			(layer "F.Fab")
			(hide yes)
			(effects
				(font
					(size 1.016 1.016)
					(thickness 0.1524)
				)
			)
		)
		(duplicate_pad_numbers_are_jumpers no)
		(fp_line
			(start 0.508 -0.9398)
			(end -0.508 -0.9398)
			(stroke
				(width 0.1524)
				(type default)
			)
			(layer "F.SilkS")
		)
		(fp_line
			(start -0.508 -0.9398)
			(end -0.508 0.9398)
			(stroke
				(width 0.1524)
				(type default)
			)
			(layer "F.SilkS")
		)
		(fp_rect
			(start -0.508 0.9398)
			(end 0.508 -0.9398)
			(stroke
				(width 0)
				(type default)
			)
			(fill no)
			(layer "F.CrtYd")
		)
		(fp_rect
			(start -0.508 0.9398)
			(end 0.508 -0.9398)
			(stroke
				(width 0)
				(type default)
			)
			(fill no)
			(layer "F.Fab")
		)
		(pad "1" smd custom
			(at 0 -0.4445 180)
			(size 0.1397 0.1397)
			(layers "F.Cu" "F.Mask" "F.Paste")
			(net "VS4_LED")
			(options
				(clearance outline)
				(anchor circle)
			)
			(primitives
				(gr_poly
					(pts
						(arc
							(start -0.1778 -0.2794)
							(mid -0.249642 -0.249642)
							(end -0.2794 -0.1778)
						)
						(arc
							(start -0.2794 0.1778)
							(mid -0.249642 0.249642)
							(end -0.1778 0.2794)
						)
						(arc
							(start 0.1778 0.2794)
							(mid 0.249642 0.249642)
							(end 0.2794 0.1778)
						)
						(arc
							(start 0.2794 -0.1778)
							(mid 0.249642 -0.249642)
							(end 0.1778 -0.2794)
						)
					)
					(width 0)
					(fill yes)
				)
			)
		)
		(pad "2" smd custom
			(at 0 0.4445 180)
			(size 0.1397 0.1397)
			(layers "F.Cu" "F.Mask" "F.Paste")
			(net "P3V3_STBY")
			(options
				(clearance outline)
				(anchor circle)
			)
			(primitives
				(gr_poly
					(pts
						(arc
							(start -0.1778 -0.2794)
							(mid -0.249642 -0.249642)
							(end -0.2794 -0.1778)
						)
						(arc
							(start -0.2794 0.1778)
							(mid -0.249642 0.249642)
							(end -0.1778 0.2794)
						)
						(arc
							(start 0.1778 0.2794)
							(mid 0.249642 0.249642)
							(end 0.2794 0.1778)
						)
						(arc
							(start 0.2794 -0.1778)
							(mid 0.249642 -0.249642)
							(end 0.1778 -0.2794)
						)
					)
					(width 0)
					(fill yes)
				)
			)
		)
	)
	(footprint ""
		(layer "F.Cu")
		(at 21.8313 -175.6791)
		(property "Reference" "Q93"
			(at 0 0 0)
			(layer "F.SilkS")
			(hide yes)
			(effects
				(font
					(size 1.27 1.27)
				)
			)
		)
		(property "Value" "2N7002K-1-GP"
			(at 0.127 -8.9662 0)
			(unlocked yes)
			(layer "F.Fab")
			(hide yes)
			(effects
				(font
					(size 1.016 1.016)
					(thickness 0.1524)
				)
			)
		)
		(property "Device Type" "SOT23DGS2D4H44"
			(at 0.127 -10.4902 0)
			(unlocked yes)
			(layer "F.Fab")
			(hide yes)
			(effects
				(font
					(size 1.016 1.016)
					(thickness 0.1524)
				)
			)
		)
		(duplicate_pad_numbers_are_jumpers no)
		(fp_line
			(start -1.651 -1.778)
			(end -1.651 1.778)
			(stroke
				(width 0.1524)
				(type default)
			)
			(layer "F.SilkS")
		)
		(fp_line
			(start -1.651 1.778)
			(end 1.651 1.778)
			(stroke
				(width 0.1524)
				(type default)
			)
			(layer "F.SilkS")
		)
		(fp_line
			(start 1.651 -1.778)
			(end -1.651 -1.778)
			(stroke
				(width 0.1524)
				(type default)
			)
			(layer "F.SilkS")
		)
		(fp_line
			(start 1.651 1.778)
			(end 1.651 -1.778)
			(stroke
				(width 0.1524)
				(type default)
			)
			(layer "F.SilkS")
		)
		(fp_poly
			(pts
				(xy -1.778 1.8796) (xy -1.778 -1.8796) (xy 1.778 -1.8796) (xy 1.778 1.8796)
			)
			(stroke
				(width 0)
				(type default)
			)
			(fill no)
			(layer "F.CrtYd")
		)
		(fp_poly
			(pts
				(xy -1.778 1.8796) (xy -1.778 -1.8796) (xy 1.778 -1.8796) (xy 1.778 1.8796)
			)
			(stroke
				(width 0)
				(type default)
			)
			(fill no)
			(layer "F.Fab")
		)
		(pad "D" smd custom
			(at 0 -0.9525)
			(size 0.1905 0.1905)
			(layers "F.Cu" "F.Mask" "F.Paste")
			(net "MATED_P12V_EN")
			(options
				(clearance outline)
				(anchor circle)
			)
			(primitives
				(gr_poly
					(pts
						(arc
							(start -0.1778 0.5715)
							(mid -0.321484 0.511984)
							(end -0.381 0.3683)
						)
						(arc
							(start -0.381 -0.3683)
							(mid -0.321484 -0.511984)
							(end -0.1778 -0.5715)
						)
						(arc
							(start 0.1778 -0.5715)
							(mid 0.321484 -0.511984)
							(end 0.381 -0.3683)
						)
						(arc
							(start 0.381 0.3683)
							(mid 0.321484 0.511984)
							(end 0.1778 0.5715)
						)
					)
					(width 0)
					(fill yes)
				)
			)
		)
		(pad "G" smd custom
			(at -0.98425 0.9525)
			(size 0.1905 0.1905)
			(layers "F.Cu" "F.Mask" "F.Paste")
			(net "PCIE_MATED#_B")
			(options
				(clearance outline)
				(anchor circle)
			)
			(primitives
				(gr_poly
					(pts
						(arc
							(start -0.1778 0.5715)
							(mid -0.321484 0.511984)
							(end -0.381 0.3683)
						)
						(arc
							(start -0.381 -0.3683)
							(mid -0.321484 -0.511984)
							(end -0.1778 -0.5715)
						)
						(arc
							(start 0.1778 -0.5715)
							(mid 0.321484 -0.511984)
							(end 0.381 -0.3683)
						)
						(arc
							(start 0.381 0.3683)
							(mid 0.321484 0.511984)
							(end 0.1778 0.5715)
						)
					)
					(width 0)
					(fill yes)
				)
			)
		)
		(pad "S" smd custom
			(at 0.98425 0.9525)
			(size 0.1905 0.1905)
			(layers "F.Cu" "F.Mask" "F.Paste")
			(net "GND")
			(options
				(clearance outline)
				(anchor circle)
			)
			(primitives
				(gr_poly
					(pts
						(arc
							(start -0.1778 0.5715)
							(mid -0.321484 0.511984)
							(end -0.381 0.3683)
						)
						(arc
							(start -0.381 -0.3683)
							(mid -0.321484 -0.511984)
							(end -0.1778 -0.5715)
						)
						(arc
							(start 0.1778 -0.5715)
							(mid 0.321484 -0.511984)
							(end 0.381 -0.3683)
						)
						(arc
							(start 0.381 0.3683)
							(mid 0.321484 0.511984)
							(end 0.1778 0.5715)
						)
					)
					(width 0)
					(fill yes)
				)
			)
		)
	)
)
